# T6G (Grand Teton) — schematic netlist excerpt (pin names and nets, part order shuffled) for the footprints in the layout excerpt that follows; sources: Cadence DE-HDL packaged netlist, KiCad conversion of 04192023_DAF0TMB3IC0_F0TG_MB_C_brd_V02_OCP.brd

C9002  Q_CAP  1000PF 50V 5% EMPTY  pkg 0402  page 123 : A = PRSNT_CABLE_GPU_A3_ISO_N ; B = GND

X3  TP_TDR_4P_FTS  TP_TDR_4P_DIP EMPTY  pkg TH  page 260
  S1  = TDR_DIFF_80_IN2_DP
  P1  = T1_GND
  P2  = T1_GND
  S2  = TDR_DIFF_80_IN2_DN

(kicad_pcb
	(version 20260206)
	(generator "pcbnew")
	(generator_version "10.0")
	(general
		(thickness 1.6)
		(legacy_teardrops no)
	)
	(paper "A4")
	(title_block
		(title "04192023_DAF0TMB3IC0_F0TG_MB_C_brd_V02_OCP.brd")
		(comment 1 "Grand Teton / footprints 3703-3704 of 8354")
	)
	(layers
		(0 "F.Cu" signal "TOP")
		(4 "In1.Cu" signal "GND")
		(6 "In2.Cu" signal "IN1")
		(8 "In3.Cu" signal "GND1")
		(10 "In4.Cu" signal "IN2")
		(12 "In5.Cu" signal "GND2")
		(14 "In6.Cu" signal "IN3")
		(16 "In7.Cu" signal "GND3")
		(18 "In8.Cu" signal "VCC")
		(20 "In9.Cu" signal "VCC1")
		(22 "In10.Cu" signal "GND4")
		(24 "In11.Cu" signal "IN4")
		(26 "In12.Cu" signal "GND5")
		(28 "In13.Cu" signal "IN5")
		(30 "In14.Cu" signal "GND6")
		(32 "In15.Cu" signal "IN6")
		(34 "In16.Cu" signal "GND7")
		(2 "B.Cu" signal "BOTTOM")
		(9 "F.Adhes" user "F.Adhesive")
		(11 "B.Adhes" user "B.Adhesive")
		(13 "F.Paste" user "Package Geometry/Pastemask Top")
		(15 "B.Paste" user "Package Geometry/Pastemask Bottom")
		(5 "F.SilkS" user "Ref Des/Silkscreen Top")
		(7 "B.SilkS" user "Ref Des/Silkscreen Bottom")
		(1 "F.Mask" user "Board Geometry/Soldermask Top")
		(3 "B.Mask" user "Board Geometry/Soldermask Bottom")
		(17 "Dwgs.User" user "User.Drawings")
		(19 "Cmts.User" user "User.Comments")
		(21 "Eco1.User" user "User.Eco1")
		(23 "Eco2.User" user "User.Eco2")
		(25 "Edge.Cuts" user "Board Geometry/Outline")
		(27 "Margin" user)
		(31 "F.CrtYd" user "Package Geometry/Place Bound Top")
		(29 "B.CrtYd" user "Package Geometry/Place Bound Bottom")
		(35 "F.Fab" user "Ref Des/Assembly Top")
		(33 "B.Fab" user "Ref Des/Assembly Bottom")
	)
	(footprint ""
		(layer "F.Cu")
		(at 504.058428 -298.345606 90)
		(property "Reference" "X3"
			(at -1.94437 1.232916 0)
			(unlocked yes)
			(layer "F.SilkS")
			(effects
				(font
					(size 0.7874 0.5842)
					(thickness 0.1524)
				)
				(justify left)
			)
		)
		(property "Value" ""
			(at 0 0 90)
			(layer "F.Fab")
			(effects
				(font
					(size 1.27 1.27)
				)
			)
		)
		(property "User Part Number" "N_A"
			(at 1.30175 1.27 180)
			(unlocked yes)
			(layer "Cmts.User")
			(hide yes)
			(effects
				(font
					(size 0.635 0.4064)
					(thickness 0.1524)
				)
			)
		)
		(property "Device Type" "TP_TDR_4P_FTS_TH-TP_TDR_4P_DIP,EMPTY,TP15"
			(at 1.30175 1.27 180)
			(unlocked yes)
			(layer "F.Fab")
			(hide yes)
			(effects
				(font
					(size 0.635 0.4064)
					(thickness 0.1524)
				)
			)
		)
		(duplicate_pad_numbers_are_jumpers no)
		(fp_line
			(start 2.54 -1.27)
			(end 0 -1.27)
			(stroke
				(width 0.1524)
				(type default)
			)
			(layer "F.SilkS")
		)
		(fp_line
			(start 0 -1.27)
			(end 0 -0.635)
			(stroke
				(width 0.1524)
				(type default)
			)
			(layer "F.SilkS")
		)
		(fp_line
			(start 2.54 -1.1303)
			(end 2.54 -1.27)
			(stroke
				(width 0.1524)
				(type default)
			)
			(layer "F.SilkS")
		)
		(fp_line
			(start 0 0.635)
			(end 0 1.905)
			(stroke
				(width 0.1524)
				(type default)
			)
			(layer "F.SilkS")
		)
		(fp_line
			(start 2.54 1.4097)
			(end 2.54 1.1303)
			(stroke
				(width 0.1524)
				(type default)
			)
			(layer "F.SilkS")
		)
		(fp_line
			(start 0 3.175)
			(end 0 3.81)
			(stroke
				(width 0.1524)
				(type default)
			)
			(layer "F.SilkS")
		)
		(fp_line
			(start 2.54 3.81)
			(end 2.54 3.6703)
			(stroke
				(width 0.1524)
				(type default)
			)
			(layer "F.SilkS")
		)
		(fp_line
			(start 0 3.81)
			(end 2.54 3.81)
			(stroke
				(width 0.1524)
				(type default)
			)
			(layer "F.SilkS")
		)
		(fp_poly
			(pts
				(xy -0.761746 0) (xy -2.285746 0.762) (xy -2.285746 -0.762)
			)
			(stroke
				(width 0)
				(type default)
			)
			(fill yes)
			(layer "F.SilkS")
		)
		(fp_line
			(start 2.54 -1.27)
			(end 0 -1.27)
			(stroke
				(width 0.1)
				(type default)
			)
			(layer "F.Fab")
		)
		(fp_line
			(start 0 -1.27)
			(end 0 3.81)
			(stroke
				(width 0.1)
				(type default)
			)
			(layer "F.Fab")
		)
		(fp_line
			(start 2.54 3.81)
			(end 2.54 -1.27)
			(stroke
				(width 0.1)
				(type default)
			)
			(layer "F.Fab")
		)
		(fp_line
			(start 0 3.81)
			(end 2.54 3.81)
			(stroke
				(width 0.1)
				(type default)
			)
			(layer "F.Fab")
		)
		(fp_poly
			(pts
				(xy -0.761746 0) (xy -2.285746 -0.762) (xy -2.285746 0.762)
			)
			(stroke
				(width 0)
				(type default)
			)
			(fill yes)
			(layer "F.Fab")
		)
		(pad "1" thru_hole circle
			(at 0 0 90)
			(size 1.0033 1.0033)
			(drill 0.249936)
			(layers "*.Cu" "*.Mask")
			(remove_unused_layers no)
			(net "TDR_DIFF_80_IN2_DP")
			(clearance 0.10795)
			(thermal_gap 0.10795)
			(padstack
				(mode front_inner_back)
				(layer "Inner"
					(shape circle)
					(size 0.8001 0.8001)
					(clearance 0.1524)
				)
				(layer "B.Cu"
					(shape circle)
					(size 1.0033 1.0033)
					(clearance 0.10795)
				)
			)
		)
		(pad "2" thru_hole circle
			(at 2.54 0 90)
			(size 1.9939 1.9939)
			(drill 0.249936)
			(layers "*.Cu" "*.Mask")
			(remove_unused_layers no)
			(net "T1_GND")
			(clearance 0.10795)
			(thermal_gap 0.10795)
			(padstack
				(mode front_inner_back)
				(layer "Inner"
					(shape circle)
					(size 0.8001 0.8001)
					(clearance 0.1524)
				)
				(layer "B.Cu"
					(shape circle)
					(size 1.9939 1.9939)
					(clearance 0.10795)
				)
			)
		)
		(pad "3" thru_hole circle
			(at 2.54 2.54 90)
			(size 1.9939 1.9939)
			(drill 0.249936)
			(layers "*.Cu" "*.Mask")
			(remove_unused_layers no)
			(net "T1_GND")
			(clearance 0.10795)
			(thermal_gap 0.10795)
			(padstack
				(mode front_inner_back)
				(layer "Inner"
					(shape circle)
					(size 0.8001 0.8001)
					(clearance 0.1524)
				)
				(layer "B.Cu"
					(shape circle)
					(size 1.9939 1.9939)
					(clearance 0.10795)
				)
			)
		)
		(pad "4" thru_hole circle
			(at 0 2.54 90)
			(size 1.0033 1.0033)
			(drill 0.249936)
			(layers "*.Cu" "*.Mask")
			(remove_unused_layers no)
			(net "TDR_DIFF_80_IN2_DN")
			(clearance 0.10795)
			(thermal_gap 0.10795)
			(padstack
				(mode front_inner_back)
				(layer "Inner"
					(shape circle)
					(size 0.8001 0.8001)
					(clearance 0.1524)
				)
				(layer "B.Cu"
					(shape circle)
					(size 1.0033 1.0033)
					(clearance 0.10795)
				)
			)
		)
	)
	(footprint ""
		(layer "F.Cu")
		(at 364.314486 -409.931616 180)
		(property "Reference" "C9002"
			(at 0 0 180)
			(layer "F.SilkS")
			(hide yes)
			(effects
				(font
					(size 1.27 1.27)
				)
			)
		)
		(property "Value" ""
			(at 0 0 180)
			(layer "F.Fab")
			(effects
				(font
					(size 1.27 1.27)
				)
			)
		)
		(duplicate_pad_numbers_are_jumpers no)
		(fp_line
			(start 0.7874 0.4064)
			(end -0.7874 0.4064)
			(stroke
				(width 0.1524)
				(type default)
			)
			(layer "F.SilkS")
		)
		(fp_line
			(start 0.7874 -0.4064)
			(end 0.7874 0.4064)
			(stroke
				(width 0.1524)
				(type default)
			)
			(layer "F.SilkS")
		)
		(fp_line
			(start -0.7874 0.4064)
			(end -0.7874 -0.4064)
			(stroke
				(width 0.1524)
				(type default)
			)
			(layer "F.SilkS")
		)
		(fp_line
			(start -0.7874 -0.4064)
			(end 0.7874 -0.4064)
			(stroke
				(width 0.1524)
				(type default)
			)
			(layer "F.SilkS")
		)
		(fp_line
			(start 0.67945 0.3048)
			(end 0.120396 0.3048)
			(stroke
				(width 0.1)
				(type default)
			)
			(layer "F.Fab")
		)
		(fp_line
			(start 0.67945 -0.3048)
			(end 0.67945 0.3048)
			(stroke
				(width 0.1)
				(type default)
			)
			(layer "F.Fab")
		)
		(fp_line
			(start 0.12065 -0.2794)
			(end 0.12065 -0.3048)
			(stroke
				(width 0.1)
				(type default)
			)
			(layer "F.Fab")
		)
		(fp_line
			(start 0.12065 -0.3048)
			(end 0.67945 -0.3048)
			(stroke
				(width 0.1)
				(type default)
			)
			(layer "F.Fab")
		)
		(fp_line
			(start 0.120396 0.3048)
			(end 0.120396 0.2794)
			(stroke
				(width 0.1)
				(type default)
			)
			(layer "F.Fab")
		)
		(fp_line
			(start 0.120396 0.2794)
			(end -0.12065 0.2794)
			(stroke
				(width 0.1)
				(type default)
			)
			(layer "F.Fab")
		)
		(fp_line
			(start -0.12065 0.3048)
			(end -0.67945 0.3048)
			(stroke
				(width 0.1)
				(type default)
			)
			(layer "F.Fab")
		)
		(fp_line
			(start -0.12065 0.2794)
			(end -0.12065 0.3048)
			(stroke
				(width 0.1)
				(type default)
			)
			(layer "F.Fab")
		)
		(fp_line
			(start -0.12065 -0.2794)
			(end 0.12065 -0.2794)
			(stroke
				(width 0.1)
				(type default)
			)
			(layer "F.Fab")
		)
		(fp_line
			(start -0.12065 -0.305054)
			(end -0.12065 -0.2794)
			(stroke
				(width 0.1)
				(type default)
			)
			(layer "F.Fab")
		)
		(fp_line
			(start -0.67945 0.3048)
			(end -0.67945 -0.305054)
			(stroke
				(width 0.1)
				(type default)
			)
			(layer "F.Fab")
		)
		(fp_line
			(start -0.67945 -0.305054)
			(end -0.12065 -0.305054)
			(stroke
				(width 0.1)
				(type default)
			)
			(layer "F.Fab")
		)
		(pad "1" smd circle
			(at -0.40005 0 180)
			(size 0 0)
			(layers "F.Cu" "F.Mask" "F.Paste")
			(net "PRSNT_CABLE_GPU_A3_ISO_N")
		)
		(pad "2" smd circle
			(at 0.40005 0 180)
			(size 0 0)
			(layers "F.Cu" "F.Mask" "F.Paste")
			(net "GND")
		)
	)
)
